# SCM (Grand Teton) — schematic netlist excerpt (pin names and nets, part order shuffled) for the footprints in the layout excerpt that follows; sources: Cadence DE-HDL packaged netlist, KiCad conversion of 12092022_DA0F0TMDCD0_F0T_Management_Board_D_brd_V3_OCP.brd

C214  Q_CAP  100PF 50V 5% EMPTY  pkg 0402  page 23 : A = V_BMC_LS_DDC_SCL_R ; B = GND
R90  Q_RES  4.7K 1% EMPTY  pkg 0402LF  page 21 : A = P3V3_AUX ; B = RST_SPI_BMC_FLASH_R2_N

(kicad_pcb
	(version 20260206)
	(generator "pcbnew")
	(generator_version "10.0")
	(general
		(thickness 1.6)
		(legacy_teardrops no)
	)
	(paper "A4")
	(title_block
		(title "12092022_DA0F0TMDCD0_F0T_Management_Board_D_brd_V3_OCP.brd")
		(comment 1 "Grand Teton / footprints 356-357 of 1440")
	)
	(layers
		(0 "F.Cu" signal "TOP")
		(4 "In1.Cu" signal "GND")
		(6 "In2.Cu" signal "IN1")
		(8 "In3.Cu" signal "GND1")
		(10 "In4.Cu" signal "IN2")
		(12 "In5.Cu" signal "VCC")
		(14 "In6.Cu" signal "VCC1")
		(16 "In7.Cu" signal "IN3")
		(18 "In8.Cu" signal "GND2")
		(20 "In9.Cu" signal "IN4")
		(22 "In10.Cu" signal "GND3")
		(2 "B.Cu" signal "BOTTOM")
		(9 "F.Adhes" user "F.Adhesive")
		(11 "B.Adhes" user "B.Adhesive")
		(13 "F.Paste" user "Package Geometry/Pastemask Top")
		(15 "B.Paste" user "Package Geometry/Pastemask Bottom")
		(5 "F.SilkS" user "Ref Des/Silkscreen Top")
		(7 "B.SilkS" user "Ref Des/Silkscreen Bottom")
		(1 "F.Mask" user "Board Geometry/Soldermask Top")
		(3 "B.Mask" user "Board Geometry/Soldermask Bottom")
		(17 "Dwgs.User" user "User.Drawings")
		(19 "Cmts.User" user "User.Comments")
		(21 "Eco1.User" user "User.Eco1")
		(23 "Eco2.User" user "User.Eco2")
		(25 "Edge.Cuts" user "Board Geometry/Outline")
		(27 "Margin" user)
		(31 "F.CrtYd" user "Package Geometry/Place Bound Top")
		(29 "B.CrtYd" user "Package Geometry/Place Bound Bottom")
		(35 "F.Fab" user "Ref Des/Assembly Top")
		(33 "B.Fab" user "Ref Des/Assembly Bottom")
	)
	(footprint ""
		(layer "F.Cu")
		(at 20.193 -68.834 -90)
		(property "Reference" "R90"
			(at 0 0 270)
			(layer "F.SilkS")
			(hide yes)
			(effects
				(font
					(size 1.27 1.27)
				)
			)
		)
		(property "Value" ""
			(at 0 0 270)
			(layer "F.Fab")
			(effects
				(font
					(size 1.27 1.27)
				)
			)
		)
		(duplicate_pad_numbers_are_jumpers no)
		(fp_line
			(start -0.7874 0.4064)
			(end -0.7874 -0.4064)
			(stroke
				(width 0.1524)
				(type default)
			)
			(layer "F.SilkS")
		)
		(fp_line
			(start 0.7874 0.4064)
			(end -0.7874 0.4064)
			(stroke
				(width 0.1524)
				(type default)
			)
			(layer "F.SilkS")
		)
		(fp_line
			(start -0.7874 -0.4064)
			(end 0.7874 -0.4064)
			(stroke
				(width 0.1524)
				(type default)
			)
			(layer "F.SilkS")
		)
		(fp_line
			(start 0.7874 -0.4064)
			(end 0.7874 0.4064)
			(stroke
				(width 0.1524)
				(type default)
			)
			(layer "F.SilkS")
		)
		(fp_line
			(start -0.67945 0.3048)
			(end -0.67945 -0.305054)
			(stroke
				(width 0.1)
				(type default)
			)
			(layer "F.Fab")
		)
		(fp_line
			(start -0.12065 0.3048)
			(end -0.67945 0.3048)
			(stroke
				(width 0.1)
				(type default)
			)
			(layer "F.Fab")
		)
		(fp_line
			(start 0.120396 0.3048)
			(end 0.120396 0.2794)
			(stroke
				(width 0.1)
				(type default)
			)
			(layer "F.Fab")
		)
		(fp_line
			(start 0.67945 0.3048)
			(end 0.120396 0.3048)
			(stroke
				(width 0.1)
				(type default)
			)
			(layer "F.Fab")
		)
		(fp_line
			(start -0.12065 0.2794)
			(end -0.12065 0.3048)
			(stroke
				(width 0.1)
				(type default)
			)
			(layer "F.Fab")
		)
		(fp_line
			(start 0.120396 0.2794)
			(end -0.12065 0.2794)
			(stroke
				(width 0.1)
				(type default)
			)
			(layer "F.Fab")
		)
		(fp_line
			(start -0.12065 -0.2794)
			(end 0.12065 -0.2794)
			(stroke
				(width 0.1)
				(type default)
			)
			(layer "F.Fab")
		)
		(fp_line
			(start 0.12065 -0.2794)
			(end 0.12065 -0.3048)
			(stroke
				(width 0.1)
				(type default)
			)
			(layer "F.Fab")
		)
		(fp_line
			(start 0.12065 -0.3048)
			(end 0.67945 -0.3048)
			(stroke
				(width 0.1)
				(type default)
			)
			(layer "F.Fab")
		)
		(fp_line
			(start 0.67945 -0.3048)
			(end 0.67945 0.3048)
			(stroke
				(width 0.1)
				(type default)
			)
			(layer "F.Fab")
		)
		(fp_line
			(start -0.67945 -0.305054)
			(end -0.12065 -0.305054)
			(stroke
				(width 0.1)
				(type default)
			)
			(layer "F.Fab")
		)
		(fp_line
			(start -0.12065 -0.305054)
			(end -0.12065 -0.2794)
			(stroke
				(width 0.1)
				(type default)
			)
			(layer "F.Fab")
		)
		(pad "1" smd circle
			(at -0.40005 0 270)
			(size 0 0)
			(layers "F.Cu" "F.Mask" "F.Paste")
			(net "P3V3_AUX")
		)
		(pad "2" smd circle
			(at 0.40005 0 270)
			(size 0 0)
			(layers "F.Cu" "F.Mask" "F.Paste")
			(net "RST_SPI_BMC_FLASH_R2_N")
		)
	)
	(footprint ""
		(layer "F.Cu")
		(at 27.813 -25.908 180)
		(property "Reference" "C214"
			(at 0 0 180)
			(layer "F.SilkS")
			(hide yes)
			(effects
				(font
					(size 1.27 1.27)
				)
			)
		)
		(property "Value" ""
			(at 0 0 180)
			(layer "F.Fab")
			(effects
				(font
					(size 1.27 1.27)
				)
			)
		)
		(duplicate_pad_numbers_are_jumpers no)
		(fp_line
			(start 0.7874 0.4064)
			(end -0.7874 0.4064)
			(stroke
				(width 0.1524)
				(type default)
			)
			(layer "F.SilkS")
		)
		(fp_line
			(start 0.7874 -0.4064)
			(end 0.7874 0.4064)
			(stroke
				(width 0.1524)
				(type default)
			)
			(layer "F.SilkS")
		)
		(fp_line
			(start -0.7874 0.4064)
			(end -0.7874 -0.4064)
			(stroke
				(width 0.1524)
				(type default)
			)
			(layer "F.SilkS")
		)
		(fp_line
			(start -0.7874 -0.4064)
			(end 0.7874 -0.4064)
			(stroke
				(width 0.1524)
				(type default)
			)
			(layer "F.SilkS")
		)
		(fp_line
			(start 0.67945 0.3048)
			(end 0.120396 0.3048)
			(stroke
				(width 0.1)
				(type default)
			)
			(layer "F.Fab")
		)
		(fp_line
			(start 0.67945 -0.3048)
			(end 0.67945 0.3048)
			(stroke
				(width 0.1)
				(type default)
			)
			(layer "F.Fab")
		)
		(fp_line
			(start 0.12065 -0.2794)
			(end 0.12065 -0.3048)
			(stroke
				(width 0.1)
				(type default)
			)
			(layer "F.Fab")
		)
		(fp_line
			(start 0.12065 -0.3048)
			(end 0.67945 -0.3048)
			(stroke
				(width 0.1)
				(type default)
			)
			(layer "F.Fab")
		)
		(fp_line
			(start 0.120396 0.3048)
			(end 0.120396 0.2794)
			(stroke
				(width 0.1)
				(type default)
			)
			(layer "F.Fab")
		)
		(fp_line
			(start 0.120396 0.2794)
			(end -0.12065 0.2794)
			(stroke
				(width 0.1)
				(type default)
			)
			(layer "F.Fab")
		)
		(fp_line
			(start -0.12065 0.3048)
			(end -0.67945 0.3048)
			(stroke
				(width 0.1)
				(type default)
			)
			(layer "F.Fab")
		)
		(fp_line
			(start -0.12065 0.2794)
			(end -0.12065 0.3048)
			(stroke
				(width 0.1)
				(type default)
			)
			(layer "F.Fab")
		)
		(fp_line
			(start -0.12065 -0.2794)
			(end 0.12065 -0.2794)
			(stroke
				(width 0.1)
				(type default)
			)
			(layer "F.Fab")
		)
		(fp_line
			(start -0.12065 -0.305054)
			(end -0.12065 -0.2794)
			(stroke
				(width 0.1)
				(type default)
			)
			(layer "F.Fab")
		)
		(fp_line
			(start -0.67945 0.3048)
			(end -0.67945 -0.305054)
			(stroke
				(width 0.1)
				(type default)
			)
			(layer "F.Fab")
		)
		(fp_line
			(start -0.67945 -0.305054)
			(end -0.12065 -0.305054)
			(stroke
				(width 0.1)
				(type default)
			)
			(layer "F.Fab")
		)
		(pad "1" smd circle
			(at -0.40005 0 180)
			(size 0 0)
			(layers "F.Cu" "F.Mask" "F.Paste")
			(net "V_BMC_LS_DDC_SCL_R")
		)
		(pad "2" smd circle
			(at 0.40005 0 180)
			(size 0 0)
			(layers "F.Cu" "F.Mask" "F.Paste")
			(net "GND")
		)
	)
)
